# T6G (Grand Teton) — schematic netlist excerpt (pin names and nets, part order shuffled) for the footprints in the layout excerpt that follows; sources: Cadence DE-HDL packaged netlist, KiCad conversion of 04192023_DAF0TMB3IC0_F0TG_MB_C_brd_V02_OCP.brd

PC645  Q_CAP  1UF 16V 10% X6S  pkg C0402  page 224 : A = PVDD11_S3_P1_VCC ; B = GND
C2290  Q_CAP  22UF 4V 20% X6S  pkg C0402  page 72 : A = PVDDCR_SOC_P1 ; B = GND

(kicad_pcb
	(version 20260206)
	(generator "pcbnew")
	(generator_version "10.0")
	(general
		(thickness 1.6)
		(legacy_teardrops no)
	)
	(paper "A4")
	(title_block
		(title "04192023_DAF0TMB3IC0_F0TG_MB_C_brd_V02_OCP.brd")
		(comment 1 "Grand Teton / footprints 1773-1774 of 8354")
	)
	(layers
		(0 "F.Cu" signal "TOP")
		(4 "In1.Cu" signal "GND")
		(6 "In2.Cu" signal "IN1")
		(8 "In3.Cu" signal "GND1")
		(10 "In4.Cu" signal "IN2")
		(12 "In5.Cu" signal "GND2")
		(14 "In6.Cu" signal "IN3")
		(16 "In7.Cu" signal "GND3")
		(18 "In8.Cu" signal "VCC")
		(20 "In9.Cu" signal "VCC1")
		(22 "In10.Cu" signal "GND4")
		(24 "In11.Cu" signal "IN4")
		(26 "In12.Cu" signal "GND5")
		(28 "In13.Cu" signal "IN5")
		(30 "In14.Cu" signal "GND6")
		(32 "In15.Cu" signal "IN6")
		(34 "In16.Cu" signal "GND7")
		(2 "B.Cu" signal "BOTTOM")
		(9 "F.Adhes" user "F.Adhesive")
		(11 "B.Adhes" user "B.Adhesive")
		(13 "F.Paste" user "Package Geometry/Pastemask Top")
		(15 "B.Paste" user "Package Geometry/Pastemask Bottom")
		(5 "F.SilkS" user "Ref Des/Silkscreen Top")
		(7 "B.SilkS" user "Ref Des/Silkscreen Bottom")
		(1 "F.Mask" user "Board Geometry/Soldermask Top")
		(3 "B.Mask" user "Board Geometry/Soldermask Bottom")
		(17 "Dwgs.User" user "User.Drawings")
		(19 "Cmts.User" user "User.Comments")
		(21 "Eco1.User" user "User.Eco1")
		(23 "Eco2.User" user "User.Eco2")
		(25 "Edge.Cuts" user "Board Geometry/Outline")
		(27 "Margin" user)
		(31 "F.CrtYd" user "Package Geometry/Place Bound Top")
		(29 "B.CrtYd" user "Package Geometry/Place Bound Bottom")
		(35 "F.Fab" user "Ref Des/Assembly Top")
		(33 "B.Fab" user "Ref Des/Assembly Bottom")
	)
	(footprint ""
		(layer "F.Cu")
		(at 167.527986 -352.26371 90)
		(property "Reference" "PC645"
			(at 0 0 90)
			(layer "F.SilkS")
			(hide yes)
			(effects
				(font
					(size 1.27 1.27)
				)
			)
		)
		(property "Value" ""
			(at 0 0 90)
			(layer "F.Fab")
			(effects
				(font
					(size 1.27 1.27)
				)
			)
		)
		(duplicate_pad_numbers_are_jumpers no)
		(fp_line
			(start 0.7874 -0.4064)
			(end 0.7874 0.4064)
			(stroke
				(width 0.1524)
				(type default)
			)
			(layer "F.SilkS")
		)
		(fp_line
			(start -0.7874 -0.4064)
			(end 0.7874 -0.4064)
			(stroke
				(width 0.1524)
				(type default)
			)
			(layer "F.SilkS")
		)
		(fp_line
			(start 0.7874 0.4064)
			(end -0.7874 0.4064)
			(stroke
				(width 0.1524)
				(type default)
			)
			(layer "F.SilkS")
		)
		(fp_line
			(start -0.7874 0.4064)
			(end -0.7874 -0.4064)
			(stroke
				(width 0.1524)
				(type default)
			)
			(layer "F.SilkS")
		)
		(fp_line
			(start -0.12065 -0.305054)
			(end -0.12065 -0.2794)
			(stroke
				(width 0.1)
				(type default)
			)
			(layer "F.Fab")
		)
		(fp_line
			(start -0.67945 -0.305054)
			(end -0.12065 -0.305054)
			(stroke
				(width 0.1)
				(type default)
			)
			(layer "F.Fab")
		)
		(fp_line
			(start 0.67945 -0.3048)
			(end 0.67945 0.3048)
			(stroke
				(width 0.1)
				(type default)
			)
			(layer "F.Fab")
		)
		(fp_line
			(start 0.12065 -0.3048)
			(end 0.67945 -0.3048)
			(stroke
				(width 0.1)
				(type default)
			)
			(layer "F.Fab")
		)
		(fp_line
			(start 0.12065 -0.2794)
			(end 0.12065 -0.3048)
			(stroke
				(width 0.1)
				(type default)
			)
			(layer "F.Fab")
		)
		(fp_line
			(start -0.12065 -0.2794)
			(end 0.12065 -0.2794)
			(stroke
				(width 0.1)
				(type default)
			)
			(layer "F.Fab")
		)
		(fp_line
			(start 0.120396 0.2794)
			(end -0.12065 0.2794)
			(stroke
				(width 0.1)
				(type default)
			)
			(layer "F.Fab")
		)
		(fp_line
			(start -0.12065 0.2794)
			(end -0.12065 0.3048)
			(stroke
				(width 0.1)
				(type default)
			)
			(layer "F.Fab")
		)
		(fp_line
			(start 0.67945 0.3048)
			(end 0.120396 0.3048)
			(stroke
				(width 0.1)
				(type default)
			)
			(layer "F.Fab")
		)
		(fp_line
			(start 0.120396 0.3048)
			(end 0.120396 0.2794)
			(stroke
				(width 0.1)
				(type default)
			)
			(layer "F.Fab")
		)
		(fp_line
			(start -0.12065 0.3048)
			(end -0.67945 0.3048)
			(stroke
				(width 0.1)
				(type default)
			)
			(layer "F.Fab")
		)
		(fp_line
			(start -0.67945 0.3048)
			(end -0.67945 -0.305054)
			(stroke
				(width 0.1)
				(type default)
			)
			(layer "F.Fab")
		)
		(pad "1" smd circle
			(at -0.40005 0 90)
			(size 0 0)
			(layers "F.Cu" "F.Mask" "F.Paste")
			(net "PVDD11_S3_P1_VCC")
		)
		(pad "2" smd circle
			(at 0.40005 0 90)
			(size 0 0)
			(layers "F.Cu" "F.Mask" "F.Paste")
			(net "GND")
		)
	)
	(footprint ""
		(layer "F.Cu")
		(at 117.895624 -256.505456 180)
		(property "Reference" "C2290"
			(at 0 0 180)
			(layer "F.SilkS")
			(hide yes)
			(effects
				(font
					(size 1.27 1.27)
				)
			)
		)
		(property "Value" ""
			(at 0 0 180)
			(layer "F.Fab")
			(effects
				(font
					(size 1.27 1.27)
				)
			)
		)
		(duplicate_pad_numbers_are_jumpers no)
		(fp_line
			(start 0.7874 0.4064)
			(end -0.7874 0.4064)
			(stroke
				(width 0.1524)
				(type default)
			)
			(layer "F.SilkS")
		)
		(fp_line
			(start 0.7874 -0.4064)
			(end 0.7874 0.4064)
			(stroke
				(width 0.1524)
				(type default)
			)
			(layer "F.SilkS")
		)
		(fp_line
			(start -0.7874 0.4064)
			(end -0.7874 -0.4064)
			(stroke
				(width 0.1524)
				(type default)
			)
			(layer "F.SilkS")
		)
		(fp_line
			(start -0.7874 -0.4064)
			(end 0.7874 -0.4064)
			(stroke
				(width 0.1524)
				(type default)
			)
			(layer "F.SilkS")
		)
		(fp_line
			(start 0.67945 0.3048)
			(end 0.120396 0.3048)
			(stroke
				(width 0.1)
				(type default)
			)
			(layer "F.Fab")
		)
		(fp_line
			(start 0.67945 -0.3048)
			(end 0.67945 0.3048)
			(stroke
				(width 0.1)
				(type default)
			)
			(layer "F.Fab")
		)
		(fp_line
			(start 0.12065 -0.2794)
			(end 0.12065 -0.3048)
			(stroke
				(width 0.1)
				(type default)
			)
			(layer "F.Fab")
		)
		(fp_line
			(start 0.12065 -0.3048)
			(end 0.67945 -0.3048)
			(stroke
				(width 0.1)
				(type default)
			)
			(layer "F.Fab")
		)
		(fp_line
			(start 0.120396 0.3048)
			(end 0.120396 0.2794)
			(stroke
				(width 0.1)
				(type default)
			)
			(layer "F.Fab")
		)
		(fp_line
			(start 0.120396 0.2794)
			(end -0.12065 0.2794)
			(stroke
				(width 0.1)
				(type default)
			)
			(layer "F.Fab")
		)
		(fp_line
			(start -0.12065 0.3048)
			(end -0.67945 0.3048)
			(stroke
				(width 0.1)
				(type default)
			)
			(layer "F.Fab")
		)
		(fp_line
			(start -0.12065 0.2794)
			(end -0.12065 0.3048)
			(stroke
				(width 0.1)
				(type default)
			)
			(layer "F.Fab")
		)
		(fp_line
			(start -0.12065 -0.2794)
			(end 0.12065 -0.2794)
			(stroke
				(width 0.1)
				(type default)
			)
			(layer "F.Fab")
		)
		(fp_line
			(start -0.12065 -0.305054)
			(end -0.12065 -0.2794)
			(stroke
				(width 0.1)
				(type default)
			)
			(layer "F.Fab")
		)
		(fp_line
			(start -0.67945 0.3048)
			(end -0.67945 -0.305054)
			(stroke
				(width 0.1)
				(type default)
			)
			(layer "F.Fab")
		)
		(fp_line
			(start -0.67945 -0.305054)
			(end -0.12065 -0.305054)
			(stroke
				(width 0.1)
				(type default)
			)
			(layer "F.Fab")
		)
		(pad "1" smd circle
			(at -0.40005 0 180)
			(size 0 0)
			(layers "F.Cu" "F.Mask" "F.Paste")
			(net "PVDDCR_SOC_P1")
		)
		(pad "2" smd circle
			(at 0.40005 0 180)
			(size 0 0)
			(layers "F.Cu" "F.Mask" "F.Paste")
			(net "GND")
		)
	)
)
